FILE_TYPE = CONNECTIVITY;
{Allegro Design Entry HDL 16.6-p007 (v16-6-112F) 10/10/2012}
"PAGE_NUMBER" = 129;
0"NC";
1"DMI_CPU0_PCH_RX_C_DN<3:0>";
2"DMI_CPU0_PCH_RX_DN<3:0>";
3"DMI_CPU0_PCH_RX_DP<3:0>";
4"DMI_CPU0_PCH_TX_DP<3:0>";
5"DMI_CPU0_PCH_TX_C_DN<3:0>";
6"DMI_CPU0_PCH_TX_DN<3:0>";
7"DMI_CPU0_PCH_TX_C_DP<3:0>";
8"DMI_CPU0_PCH_RX_C_DP<3:0>";
9"DMI_CPU0_PCH_RX_C_DP<2>";
10"DMI_CPU0_PCH_TX_DP<1>";
11"DMI_CPU0_PCH_RX_C_DN<3>";
12"DMI_CPU0_PCH_TX_C_DN<1>";
13"DMI_CPU0_PCH_TX_DN<2>";
14"DMI_CPU0_PCH_RX_C_DP<1>";
15"DMI_CPU0_PCH_RX_C_DP<0>";
16"DMI_CPU0_PCH_RX_C_DP<3>";
17"DMI_CPU0_PCH_TX_DP<0>";
18"DMI_CPU0_PCH_RX_DN<2>";
19"DMI_CPU0_PCH_TX_C_DN<0>";
20"DMI_CPU0_PCH_TX_DN<0>";
21"DMI_CPU0_PCH_TX_C_DP<2>";
22"DMI_CPU0_PCH_TX_C_DP<3>";
23"DMI_CPU0_PCH_TX_DP<2>";
24"DMI_CPU0_PCH_TX_C_DP<1>";
25"DMI_CPU0_PCH_TX_C_DP<0>";
26"DMI_CPU0_PCH_TX_C_DN<3>";
27"DMI_CPU0_PCH_TX_DN<3>";
28"DMI_CPU0_PCH_TX_DN<1>";
29"DMI_CPU0_PCH_RX_C_DN<2>";
30"DMI_CPU0_PCH_TX_C_DN<2>";
31"DMI_CPU0_PCH_TX_DP<3>";
32"DMI_CPU0_PCH_RX_DP<0>";
33"DMI_CPU0_PCH_RX_DP<1>";
34"DMI_CPU0_PCH_RX_DP<2>";
35"DMI_CPU0_PCH_RX_DP<3>";
36"DMI_CPU0_PCH_RX_DN<0>";
37"DMI_CPU0_PCH_RX_DN<1>";
38"DMI_CPU0_PCH_RX_DN<3>";
39"DMI_CPU0_PCH_RX_C_DN<0>";
40"DMI_CPU0_PCH_RX_C_DN<1>";
%"TAP"
"6","(1200,3975)","2","mstr_standard","I11";
;
BOM_COST"SB"
CDS_LIB"mstr_standard"
BODY_TYPE"PLUMBING"
HDL_TAP"TRUE";
"B \NAC \NWC"1;
"S \NAC"
BN"3"11;
%"TAP"
"6","(1200,3775)","2","mstr_standard","I12";
;
BOM_COST"SB"
CDS_LIB"mstr_standard"
BODY_TYPE"PLUMBING"
HDL_TAP"TRUE";
"B \NAC \NWC"1;
"S \NAC"
BN"2"29;
%"TAP"
"6","(1200,3375)","2","mstr_standard","I13";
;
BOM_COST"SB"
CDS_LIB"mstr_standard"
BODY_TYPE"PLUMBING"
HDL_TAP"TRUE";
"B \NAC \NWC"1;
"S \NAC"
BN"0"39;
%"TAP"
"6","(1200,3575)","2","mstr_standard","I14";
;
BOM_COST"SB"
CDS_LIB"mstr_standard"
BODY_TYPE"PLUMBING"
HDL_TAP"TRUE";
"B \NAC \NWC"1;
"S \NAC"
BN"1"40;
%"TAP"
"6","(1200,4925)","2","mstr_standard","I2";
;
BOM_COST"SB"
CDS_LIB"mstr_standard"
BODY_TYPE"PLUMBING"
HDL_TAP"TRUE";
"B \NAC \NWC"5;
"S \NAC"
BN"3"26;
%"TAP"
"1","(-125,4925)","2","mstr_standard","I23";
;
BOM_COST"SB"
CDS_LIB"mstr_standard"
BODY_TYPE"PLUMBING"
HDL_TAP"TRUE";
"B \NAC \NWC"6;
"S \NAC"
BN"3"27;
%"TAP"
"1","(-125,4725)","2","mstr_standard","I24";
;
BOM_COST"SB"
CDS_LIB"mstr_standard"
BODY_TYPE"PLUMBING"
HDL_TAP"TRUE";
"B \NAC \NWC"6;
"S \NAC"
BN"2"13;
%"TAP"
"1","(-125,4525)","2","mstr_standard","I25";
;
BOM_COST"SB"
CDS_LIB"mstr_standard"
BODY_TYPE"PLUMBING"
HDL_TAP"TRUE";
"B \NAC \NWC"6;
"S \NAC"
BN"1"28;
%"TAP"
"1","(-125,4325)","2","mstr_standard","I26";
;
BOM_COST"SB"
CDS_LIB"mstr_standard"
BODY_TYPE"PLUMBING"
HDL_TAP"TRUE";
"B \NAC \NWC"6;
"S \NAC"
BN"0"20;
%"TAP"
"6","(-2800,4925)","2","mstr_standard","I29";
;
BOM_COST"SB"
CDS_LIB"mstr_standard"
BODY_TYPE"PLUMBING"
HDL_TAP"TRUE";
"B \NAC \NWC"7;
"S \NAC"
BN"3"22;
%"TAP"
"6","(1200,4725)","2","mstr_standard","I3";
;
BOM_COST"SB"
CDS_LIB"mstr_standard"
BODY_TYPE"PLUMBING"
HDL_TAP"TRUE";
"B \NAC \NWC"5;
"S \NAC"
BN"2"30;
%"TAP"
"6","(-2800,4725)","2","mstr_standard","I30";
;
BOM_COST"SB"
CDS_LIB"mstr_standard"
BODY_TYPE"PLUMBING"
HDL_TAP"TRUE";
"B \NAC \NWC"7;
"S \NAC"
BN"2"21;
%"TAP"
"6","(-2800,4525)","2","mstr_standard","I31";
;
BOM_COST"SB"
CDS_LIB"mstr_standard"
BODY_TYPE"PLUMBING"
HDL_TAP"TRUE";
"B \NAC \NWC"7;
"S \NAC"
BN"1"24;
%"TAP"
"6","(-2800,4325)","2","mstr_standard","I32";
;
BOM_COST"SB"
CDS_LIB"mstr_standard"
BODY_TYPE"PLUMBING"
HDL_TAP"TRUE";
"B \NAC \NWC"7;
"S \NAC"
BN"0"25;
%"CAP"
"1","(-3650,4925)","1","mstr_discrete","I35";
;
LOCATION"C7B25"
VALUE"0.22UF"
TOLERANCE"10%"
PACK_TYPE"0402"
MATERIAL"X7R"
VOLTAGE"16V"
PART_NUMBER"A36096-155"
BOM_COST"SB"
CDS_LIB"mstr_discrete"
CDS_SEC"1"
$SEC"1"
CDS_LOCATION"C7B25"
ROOM"DMI";
"A"
$PN"1"31;
"B"
$PN"2"22;
%"TAP"
"1","(-150,3975)","2","mstr_standard","I37";
;
BOM_COST"SB"
CDS_LIB"mstr_standard"
BODY_TYPE"PLUMBING"
HDL_TAP"TRUE";
"B \NAC \NWC"2;
"S \NAC"
BN"3"38;
%"TAP"
"1","(-150,3775)","2","mstr_standard","I38";
;
BOM_COST"SB"
CDS_LIB"mstr_standard"
BODY_TYPE"PLUMBING"
HDL_TAP"TRUE";
"B \NAC \NWC"2;
"S \NAC"
BN"2"18;
%"TAP"
"1","(-150,3375)","2","mstr_standard","I39";
;
BOM_COST"SB"
CDS_LIB"mstr_standard"
BODY_TYPE"PLUMBING"
HDL_TAP"TRUE";
"B \NAC \NWC"2;
"S \NAC"
BN"0"36;
%"TAP"
"6","(1200,4525)","2","mstr_standard","I4";
;
BOM_COST"SB"
CDS_LIB"mstr_standard"
BODY_TYPE"PLUMBING"
HDL_TAP"TRUE";
"B \NAC \NWC"5;
"S \NAC"
BN"1"12;
%"TAP"
"1","(-150,3575)","2","mstr_standard","I40";
;
BOM_COST"SB"
CDS_LIB"mstr_standard"
BODY_TYPE"PLUMBING"
HDL_TAP"TRUE";
"B \NAC \NWC"2;
"S \NAC"
BN"1"37;
%"TAP"
"6","(-2800,3975)","2","mstr_standard","I45";
;
BOM_COST"SB"
CDS_LIB"mstr_standard"
BODY_TYPE"PLUMBING"
HDL_TAP"TRUE";
"B \NAC \NWC"8;
"S \NAC"
BN"3"16;
%"TAP"
"6","(-2800,3775)","2","mstr_standard","I46";
;
BOM_COST"SB"
CDS_LIB"mstr_standard"
BODY_TYPE"PLUMBING"
HDL_TAP"TRUE";
"B \NAC \NWC"8;
"S \NAC"
BN"2"9;
%"TAP"
"6","(-2800,3375)","2","mstr_standard","I47";
;
BOM_COST"SB"
CDS_LIB"mstr_standard"
BODY_TYPE"PLUMBING"
HDL_TAP"TRUE";
"B \NAC \NWC"8;
"S \NAC"
BN"0"15;
%"TAP"
"6","(-2800,3575)","2","mstr_standard","I48";
;
BOM_COST"SB"
CDS_LIB"mstr_standard"
BODY_TYPE"PLUMBING"
HDL_TAP"TRUE";
"B \NAC \NWC"8;
"S \NAC"
BN"1"14;
%"TAP"
"6","(1200,4325)","2","mstr_standard","I5";
;
BOM_COST"SB"
CDS_LIB"mstr_standard"
BODY_TYPE"PLUMBING"
HDL_TAP"TRUE";
"B \NAC \NWC"5;
"S \NAC"
BN"0"19;
%"TAP"
"1","(-4150,4925)","2","mstr_standard","I57";
;
BOM_COST"SB"
CDS_LIB"mstr_standard"
BODY_TYPE"PLUMBING"
HDL_TAP"TRUE";
"B \NAC \NWC"4;
"S \NAC"
BN"3"31;
%"TAP"
"1","(-4150,4725)","2","mstr_standard","I58";
;
BOM_COST"SB"
CDS_LIB"mstr_standard"
BODY_TYPE"PLUMBING"
HDL_TAP"TRUE";
"B \NAC \NWC"4;
"S \NAC"
BN"2"23;
%"TAP"
"1","(-4150,4525)","2","mstr_standard","I59";
;
BOM_COST"SB"
CDS_LIB"mstr_standard"
BODY_TYPE"PLUMBING"
HDL_TAP"TRUE";
"B \NAC \NWC"4;
"S \NAC"
BN"1"10;
%"TAP"
"1","(-4150,4325)","2","mstr_standard","I60";
;
BOM_COST"SB"
CDS_LIB"mstr_standard"
BODY_TYPE"PLUMBING"
HDL_TAP"TRUE";
"B \NAC \NWC"4;
"S \NAC"
BN"0"17;
%"TAP"
"1","(-4150,3975)","2","mstr_standard","I62";
;
BOM_COST"SB"
CDS_LIB"mstr_standard"
BODY_TYPE"PLUMBING"
HDL_TAP"TRUE";
"B \NAC \NWC"3;
"S \NAC"
BN"3"35;
%"TAP"
"1","(-4150,3775)","2","mstr_standard","I63";
;
BOM_COST"SB"
CDS_LIB"mstr_standard"
BODY_TYPE"PLUMBING"
HDL_TAP"TRUE";
"B \NAC \NWC"3;
"S \NAC"
BN"2"34;
%"TAP"
"1","(-4150,3375)","2","mstr_standard","I64";
;
BOM_COST"SB"
CDS_LIB"mstr_standard"
BODY_TYPE"PLUMBING"
HDL_TAP"TRUE";
"B \NAC \NWC"3;
"S \NAC"
BN"0"32;
%"TAP"
"1","(-4150,3575)","2","mstr_standard","I65";
;
BOM_COST"SB"
CDS_LIB"mstr_standard"
BODY_TYPE"PLUMBING"
HDL_TAP"TRUE";
"B \NAC \NWC"3;
"S \NAC"
BN"1"33;
%"CAP"
"1","(-3300,4725)","1","mstr_discrete","I69";
;
VALUE"0.22UF"
TOLERANCE"10%"
LOCATION"C7B27"
PART_NUMBER"A36096-155"
VOLTAGE"16V"
MATERIAL"X7R"
PACK_TYPE"0402"
BOM_COST"SB"
CDS_LIB"mstr_discrete"
CDS_SEC"1"
$SEC"1"
CDS_LOCATION"C7B27"
ROOM"DMI";
"A"
$PN"1"23;
"B"
$PN"2"21;
%"CAP"
"1","(-3650,4525)","1","mstr_discrete","I70";
;
VALUE"0.22UF"
TOLERANCE"10%"
VOLTAGE"16V"
MATERIAL"X7R"
PACK_TYPE"0402"
PART_NUMBER"A36096-155"
LOCATION"C7B28"
BOM_COST"SB"
CDS_LIB"mstr_discrete"
CDS_SEC"1"
$SEC"1"
CDS_LOCATION"C7B28"
ROOM"DMI";
"A"
$PN"1"10;
"B"
$PN"2"24;
%"CAP"
"1","(-3300,4325)","1","mstr_discrete","I71";
;
VALUE"0.22UF"
LOCATION"C7C2"
PART_NUMBER"A36096-155"
VOLTAGE"16V"
MATERIAL"X7R"
TOLERANCE"10%"
PACK_TYPE"0402"
BOM_COST"SB"
CDS_LIB"mstr_discrete"
CDS_SEC"1"
$SEC"1"
CDS_LOCATION"C7C2"
ROOM"DMI";
"A"
$PN"1"17;
"B"
$PN"2"25;
%"CAP"
"1","(-3300,3375)","1","mstr_discrete","I72";
;
LOCATION"C3M40"
VALUE"0.22UF"
TOLERANCE"10%"
MATERIAL"X7R"
PACK_TYPE"0402"
VOLTAGE"16V"
PART_NUMBER"A36096-155"
CDS_LIB"mstr_discrete"
BOM_COST"SB"
CDS_SEC"1"
$SEC"1"
CDS_LOCATION"C3M40"
ROOM"DMI";
"A"
$PN"1"32;
"B"
$PN"2"15;
%"CAP"
"1","(-3650,3575)","1","mstr_discrete","I73";
;
LOCATION"C3M37"
PART_NUMBER"A36096-155"
VALUE"0.22UF"
TOLERANCE"10%"
PACK_TYPE"0402"
MATERIAL"X7R"
VOLTAGE"16V"
CDS_LIB"mstr_discrete"
BOM_COST"SB"
CDS_SEC"1"
$SEC"1"
CDS_LOCATION"C3M37"
ROOM"DMI";
"A"
$PN"1"33;
"B"
$PN"2"14;
%"CAP"
"1","(-3300,3775)","1","mstr_discrete","I74";
;
LOCATION"C3N9"
VALUE"0.22UF"
TOLERANCE"10%"
PACK_TYPE"0402"
MATERIAL"X7R"
PART_NUMBER"A36096-155"
VOLTAGE"16V"
CDS_LIB"mstr_discrete"
BOM_COST"SB"
CDS_SEC"1"
$SEC"1"
CDS_LOCATION"C3N9"
ROOM"DMI";
"A"
$PN"1"34;
"B"
$PN"2"9;
%"CAP"
"1","(-3650,3975)","1","mstr_discrete","I75";
;
VALUE"0.22UF"
TOLERANCE"10%"
PACK_TYPE"0402"
MATERIAL"X7R"
LOCATION"C3N8"
VOLTAGE"16V"
PART_NUMBER"A36096-155"
CDS_LIB"mstr_discrete"
BOM_COST"SB"
CDS_SEC"1"
$SEC"1"
CDS_LOCATION"C3N8"
ROOM"DMI";
"A"
$PN"1"35;
"B"
$PN"2"16;
%"CAP"
"1","(750,4325)","1","mstr_discrete","I76";
;
LOCATION"C7C3"
PART_NUMBER"A36096-155"
PACK_TYPE"0402"
TOLERANCE"10%"
VALUE"0.22UF"
MATERIAL"X7R"
VOLTAGE"16V"
CDS_LIB"mstr_discrete"
BOM_COST"SB"
CDS_SEC"1"
$SEC"1"
CDS_LOCATION"C7C3"
ROOM"DMI";
"A"
$PN"1"20;
"B"
$PN"2"19;
%"CAP"
"1","(400,4525)","1","mstr_discrete","I77";
;
MATERIAL"X7R"
PACK_TYPE"0402"
TOLERANCE"10%"
VALUE"0.22UF"
LOCATION"C7C1"
PART_NUMBER"A36096-155"
VOLTAGE"16V"
CDS_LIB"mstr_discrete"
BOM_COST"SB"
CDS_SEC"1"
$SEC"1"
CDS_LOCATION"C7C1"
ROOM"DMI";
"A"
$PN"1"28;
"B"
$PN"2"12;
%"CAP"
"1","(750,4725)","1","mstr_discrete","I78";
;
TOLERANCE"10%"
VALUE"0.22UF"
PART_NUMBER"A36096-155"
LOCATION"C7B29"
MATERIAL"X7R"
PACK_TYPE"0402"
VOLTAGE"16V"
CDS_LIB"mstr_discrete"
BOM_COST"SB"
CDS_SEC"1"
$SEC"1"
CDS_LOCATION"C7B29"
ROOM"DMI";
"A"
$PN"1"13;
"B"
$PN"2"30;
%"CAP"
"1","(400,4925)","1","mstr_discrete","I79";
;
MATERIAL"X7R"
LOCATION"C7B26"
PACK_TYPE"0402"
TOLERANCE"10%"
VALUE"0.22UF"
VOLTAGE"16V"
PART_NUMBER"A36096-155"
CDS_LIB"mstr_discrete"
BOM_COST"SB"
CDS_SEC"1"
$SEC"1"
CDS_LOCATION"C7B26"
ROOM"DMI";
"A"
$PN"1"27;
"B"
$PN"2"26;
%"CAP"
"1","(750,3375)","1","mstr_discrete","I80";
;
LOCATION"C3M44"
VALUE"0.22UF"
TOLERANCE"10%"
PACK_TYPE"0402"
MATERIAL"X7R"
VOLTAGE"16V"
PART_NUMBER"A36096-155"
CDS_LIB"mstr_discrete"
BOM_COST"SB"
CDS_SEC"1"
$SEC"1"
CDS_LOCATION"C3M44"
ROOM"DMI";
"A"
$PN"1"36;
"B"
$PN"2"39;
%"CAP"
"1","(400,3575)","1","mstr_discrete","I81";
;
PART_NUMBER"A36096-155"
VALUE"0.22UF"
TOLERANCE"10%"
PACK_TYPE"0402"
MATERIAL"X7R"
VOLTAGE"16V"
LOCATION"C3M41"
CDS_LIB"mstr_discrete"
BOM_COST"SB"
CDS_SEC"1"
$SEC"1"
CDS_LOCATION"C3M41"
ROOM"DMI";
"A"
$PN"1"37;
"B"
$PN"2"40;
%"CAP"
"1","(750,3775)","1","mstr_discrete","I82";
;
LOCATION"C3M45"
VALUE"0.22UF"
TOLERANCE"10%"
PACK_TYPE"0402"
MATERIAL"X7R"
PART_NUMBER"A36096-155"
VOLTAGE"16V"
CDS_LIB"mstr_discrete"
BOM_COST"SB"
CDS_SEC"1"
$SEC"1"
CDS_LOCATION"C3M45"
ROOM"DMI";
"A"
$PN"1"18;
"B"
$PN"2"29;
%"CAP"
"1","(400,3975)","1","mstr_discrete","I83";
;
LOCATION"C3N13"
PART_NUMBER"A36096-155"
VALUE"0.22UF"
PACK_TYPE"0402"
MATERIAL"X7R"
TOLERANCE"10%"
VOLTAGE"16V"
CDS_LIB"mstr_discrete"
BOM_COST"SB"
CDS_SEC"1"
$SEC"1"
CDS_LOCATION"C3N13"
ROOM"DMI";
"A"
$PN"1"38;
"B"
$PN"2"11;
END.
